# SCM (Grand Teton) — schematic netlist excerpt (pin names and nets, part order shuffled) for the footprints in the layout excerpt that follows; sources: Cadence DE-HDL packaged netlist, KiCad conversion of 12092022_DA0F0TMDCD0_F0T_Management_Board_D_brd_V3_OCP.brd

J9  PICOPROBE_BXA  DELTA-L 4.0 EMPTY  pkg TRIANG_LAUNCH_3PXB  page 58
  \1_p\  = 85_5INCH_TOP_DN
  \2_n\  = 85_5INCH_TOP_DP
  \3_g\  = GND_P1

(kicad_pcb
	(version 20260206)
	(generator "pcbnew")
	(generator_version "10.0")
	(general
		(thickness 1.6)
		(legacy_teardrops no)
	)
	(paper "A4")
	(title_block
		(title "12092022_DA0F0TMDCD0_F0T_Management_Board_D_brd_V3_OCP.brd")
		(comment 1 "Grand Teton / footprints 658-658 of 1440")
	)
	(layers
		(0 "F.Cu" signal "TOP")
		(4 "In1.Cu" signal "GND")
		(6 "In2.Cu" signal "IN1")
		(8 "In3.Cu" signal "GND1")
		(10 "In4.Cu" signal "IN2")
		(12 "In5.Cu" signal "VCC")
		(14 "In6.Cu" signal "VCC1")
		(16 "In7.Cu" signal "IN3")
		(18 "In8.Cu" signal "GND2")
		(20 "In9.Cu" signal "IN4")
		(22 "In10.Cu" signal "GND3")
		(2 "B.Cu" signal "BOTTOM")
		(9 "F.Adhes" user "F.Adhesive")
		(11 "B.Adhes" user "B.Adhesive")
		(13 "F.Paste" user "Package Geometry/Pastemask Top")
		(15 "B.Paste" user "Package Geometry/Pastemask Bottom")
		(5 "F.SilkS" user "Ref Des/Silkscreen Top")
		(7 "B.SilkS" user "Ref Des/Silkscreen Bottom")
		(1 "F.Mask" user "Board Geometry/Soldermask Top")
		(3 "B.Mask" user "Board Geometry/Soldermask Bottom")
		(17 "Dwgs.User" user "User.Drawings")
		(19 "Cmts.User" user "User.Comments")
		(21 "Eco1.User" user "User.Eco1")
		(23 "Eco2.User" user "User.Eco2")
		(25 "Edge.Cuts" user "Board Geometry/Outline")
		(27 "Margin" user)
		(31 "F.CrtYd" user "Package Geometry/Place Bound Top")
		(29 "B.CrtYd" user "Package Geometry/Place Bound Bottom")
		(35 "F.Fab" user "Ref Des/Assembly Top")
		(33 "B.Fab" user "Ref Des/Assembly Bottom")
	)
	(footprint ""
		(layer "F.Cu")
		(at 101.2825 -65.6336 90)
		(property "Reference" "J9"
			(at -5.1816 -1.56083 90)
			(unlocked yes)
			(layer "F.SilkS")
			(effects
				(font
					(size 0.7874 0.5842)
					(thickness 0.1524)
				)
				(justify left)
			)
		)
		(property "Value" ""
			(at 0 0 90)
			(layer "F.Fab")
			(effects
				(font
					(size 1.27 1.27)
				)
			)
		)
		(duplicate_pad_numbers_are_jumpers no)
		(fp_line
			(start 1.2192 -2.1082)
			(end 1.2192 -0.462026)
			(stroke
				(width 0.1524)
				(type default)
			)
			(layer "F.SilkS")
		)
		(fp_line
			(start -1.2192 -2.1082)
			(end 1.2192 -2.1082)
			(stroke
				(width 0.1524)
				(type default)
			)
			(layer "F.SilkS")
		)
		(fp_line
			(start 1.2192 0.454406)
			(end 1.2192 2.1082)
			(stroke
				(width 0.1524)
				(type default)
			)
			(layer "F.SilkS")
		)
		(fp_line
			(start 1.2192 2.1082)
			(end -1.2192 2.1082)
			(stroke
				(width 0.1524)
				(type default)
			)
			(layer "F.SilkS")
		)
		(fp_line
			(start -1.2192 2.1082)
			(end -1.2192 -2.1082)
			(stroke
				(width 0.1524)
				(type default)
			)
			(layer "F.SilkS")
		)
		(pad "" np_thru_hole circle
			(at -2.8829 -1.27)
			(size 1.0414 1.0414)
			(drill 1.0414)
			(layers "*.Cu" "*.Mask")
			(clearance 0.381)
			(thermal_gap 0.381)
		)
		(pad "" np_thru_hole circle
			(at -2.8829 1.27)
			(size 1.0414 1.0414)
			(drill 1.0414)
			(layers "*.Cu" "*.Mask")
			(clearance 0.381)
			(thermal_gap 0.381)
		)
		(pad "" np_thru_hole circle
			(at 3.4671 -1.27)
			(size 1.0414 1.0414)
			(drill 1.0414)
			(layers "*.Cu" "*.Mask")
			(clearance 0.381)
			(thermal_gap 0.381)
		)
		(pad "" np_thru_hole circle
			(at 3.4671 1.27)
			(size 1.0414 1.0414)
			(drill 1.0414)
			(layers "*.Cu" "*.Mask")
			(clearance 0.381)
			(thermal_gap 0.381)
		)
		(pad "1" smd rect
			(at 0.8255 -0.249936)
			(size 0.3048 0.508)
			(layers "F.Cu" "F.Mask" "F.Paste")
			(net "85_5INCH_TOP_DN")
		)
		(pad "2" smd rect
			(at 0.8255 0.249936)
			(size 0.3048 0.508)
			(layers "F.Cu" "F.Mask" "F.Paste")
			(net "85_5INCH_TOP_DP")
		)
		(pad "3" smd circle
			(at 0 0 90)
			(size 0 0)
			(layers "F.Cu" "F.Mask" "F.Paste")
			(net "GND_P1")
		)
		(zone
			(layer "F.Cu")
			(hatch none 0.5)
			(connect_pads
				(clearance 0)
			)
			(min_thickness 0.25)
			(keepout
				(tracks not_allowed)
				(vias allowed)
				(pads allowed)
				(copperpour not_allowed)
				(footprints allowed)
			)
			(placement
				(enabled no)
				(sheetname "")
			)
			(fill
				(thermal_gap 0.5)
				(thermal_bridge_width 0.5)
				(island_removal_mode 0)
			)
			(polygon
				(pts
					(xy 100.73386 -66.7512) (xy 100.829364 -66.7512) (xy 100.829364 -66.1543) (xy 101.235764 -66.1543)
					(xy 101.235764 -66.7512) (xy 101.329236 -66.7512) (xy 101.329236 -66.1543) (xy 101.735636 -66.1543)
					(xy 101.735636 -66.7512) (xy 101.83114 -66.7512) (xy 101.83114 -66.0527) (xy 100.73386 -66.0527)
				)
			)
		)
		(zone
			(layers "F.Cu" "B.Cu" "In1.Cu" "In2.Cu" "In3.Cu" "In4.Cu" "In5.Cu" "In6.Cu"
				"In7.Cu" "In8.Cu" "In9.Cu" "In10.Cu"
			)
			(hatch none 0.5)
			(connect_pads
				(clearance 0)
			)
			(min_thickness 0.25)
			(keepout
				(tracks not_allowed)
				(vias allowed)
				(pads allowed)
				(copperpour not_allowed)
				(footprints allowed)
			)
			(placement
				(enabled no)
				(sheetname "")
			)
			(fill
				(thermal_gap 0.5)
				(thermal_bridge_width 0.5)
				(island_removal_mode 0)
			)
			(polygon
				(pts
					(arc
						(start 100.9396 -69.1007)
						(mid 99.0854 -69.1007)
						(end 100.9396 -69.1007)
					)
				)
			)
		)
		(zone
			(layers "F.Cu" "B.Cu" "In1.Cu" "In2.Cu" "In3.Cu" "In4.Cu" "In5.Cu" "In6.Cu"
				"In7.Cu" "In8.Cu" "In9.Cu" "In10.Cu"
			)
			(hatch none 0.5)
			(connect_pads
				(clearance 0)
			)
			(min_thickness 0.25)
			(keepout
				(tracks not_allowed)
				(vias allowed)
				(pads allowed)
				(copperpour not_allowed)
				(footprints allowed)
			)
			(placement
				(enabled no)
				(sheetname "")
			)
			(fill
				(thermal_gap 0.5)
				(thermal_bridge_width 0.5)
				(island_removal_mode 0)
			)
			(polygon
				(pts
					(arc
						(start 100.9396 -62.7507)
						(mid 99.0854 -62.7507)
						(end 100.9396 -62.7507)
					)
				)
			)
		)
		(zone
			(layers "F.Cu" "B.Cu" "In1.Cu" "In2.Cu" "In3.Cu" "In4.Cu" "In5.Cu" "In6.Cu"
				"In7.Cu" "In8.Cu" "In9.Cu" "In10.Cu"
			)
			(hatch none 0.5)
			(connect_pads
				(clearance 0)
			)
			(min_thickness 0.25)
			(keepout
				(tracks not_allowed)
				(vias allowed)
				(pads allowed)
				(copperpour not_allowed)
				(footprints allowed)
			)
			(placement
				(enabled no)
				(sheetname "")
			)
			(fill
				(thermal_gap 0.5)
				(thermal_bridge_width 0.5)
				(island_removal_mode 0)
			)
			(polygon
				(pts
					(arc
						(start 103.4796 -69.1007)
						(mid 101.6254 -69.1007)
						(end 103.4796 -69.1007)
					)
				)
			)
		)
		(zone
			(layers "F.Cu" "B.Cu" "In1.Cu" "In2.Cu" "In3.Cu" "In4.Cu" "In5.Cu" "In6.Cu"
				"In7.Cu" "In8.Cu" "In9.Cu" "In10.Cu"
			)
			(hatch none 0.5)
			(connect_pads
				(clearance 0)
			)
			(min_thickness 0.25)
			(keepout
				(tracks not_allowed)
				(vias allowed)
				(pads allowed)
				(copperpour not_allowed)
				(footprints allowed)
			)
			(placement
				(enabled no)
				(sheetname "")
			)
			(fill
				(thermal_gap 0.5)
				(thermal_bridge_width 0.5)
				(island_removal_mode 0)
			)
			(polygon
				(pts
					(arc
						(start 103.4796 -62.7507)
						(mid 101.6254 -62.7507)
						(end 103.4796 -62.7507)
					)
				)
			)
		)
	)
)
